(kicad_pcb
	(version 20221018)
	(generator pcbnew)
	(general
    (thickness 1.518)
  )
	(paper "A4")
	(title_block
    (title "Kria K26 Devboard")
    (date "2024-03-26")
    (rev "1.2.5")
    (comment 1 "www.antmicro.com")
    (comment 2 "Antmicro Ltd.")
		(comment 9 "footprints 614-622 of 660")
	)
	(layers
    (0 "F.Cu" mixed)
    (1 "In1.Cu" power)
    (2 "In2.Cu" mixed)
    (3 "In3.Cu" power)
    (4 "In4.Cu" mixed)
    (5 "In5.Cu" power)
    (6 "In6.Cu" mixed)
    (31 "B.Cu" power)
    (32 "B.Adhes" user "B.Adhesive")
    (33 "F.Adhes" user "F.Adhesive")
    (34 "B.Paste" user)
    (35 "F.Paste" user)
    (36 "B.SilkS" user "B.Silkscreen")
    (37 "F.SilkS" user "F.Silkscreen")
    (38 "B.Mask" user)
    (39 "F.Mask" user)
    (40 "Dwgs.User" user "User.Drawings")
    (41 "Cmts.User" user "User.Comments")
    (42 "Eco1.User" user "User.Eco1")
    (43 "Eco2.User" user "User.Eco2")
    (44 "Edge.Cuts" user)
    (45 "Margin" user)
    (46 "B.CrtYd" user "B.Courtyard")
    (47 "F.CrtYd" user "F.Courtyard")
    (48 "B.Fab" user)
    (49 "F.Fab" user)
  )
	(footprint "kria-k26-devboard-footprints:R_0402_1005Metric" (layer "B.Cu")
    (at 119.2 78.97 90)
    (descr "Resistor SMD 0402")
    (tags "resistor SMD 0402")
    (property "Author" "Antmicro")
    (property "License" "Apache-2.0")
    (property "MPN" "CR0402-FX-2003GLF")
    (property "Manufacturer" "Bourns")
    (property "Sheetfile" "usb.kicad_sch")
    (property "Sheetname" "USB")
    (property "Tolerance" "1%")
    (property "Val" "200k")
    (property "ki_description" "200k resistor in 0402 package with 1% tolerance")
    (attr smd)
    (fp_text reference "R53" (at 3.065 0.38 270) (layer "B.SilkS")
        (effects (font (size 0.7 0.7) (thickness 0.15)) (justify left bottom mirror))
    )
    (fp_text value "R_200k_0402" (at 0 -1.4 270) (layer "B.Fab") hide
        (effects (font (size 0.7 0.7) (thickness 0.15)) (justify left bottom mirror))
    )
    (fp_text user "Author: Antmicro" (at -0.95 -4.169 270) (layer "B.Fab") hide
        (effects (font (size 0.7 0.7) (thickness 0.15)) (justify left bottom mirror))
    )
    (fp_text user "License: Apache-2.0" (at -0.95 -5.169 270) (layer "B.Fab") hide
        (effects (font (size 0.7 0.7) (thickness 0.15)) (justify left bottom mirror))
    )
    (fp_text user "${REFERENCE}" (at -0.95 -3.168 270) (layer "B.Fab") hide
        (effects (font (size 0.7 0.7) (thickness 0.15)) (justify left bottom mirror))
    )
    (fp_rect (start -0.93 0.47) (end 0.93 -0.47)
      (stroke (width 0.05) (type solid)) (fill none) (layer "B.CrtYd"))
    (fp_rect (start -0.5 0.25) (end 0.5 -0.25)
      (stroke (width 0.15) (type solid)) (fill none) (layer "B.Fab"))
    (pad "1" smd roundrect (at -0.485 0 90) (size 0.59 0.64) (layers "B.Cu" "B.Paste" "B.Mask") (roundrect_rratio 0.25)
      (net 1 "GND") (pintype "passive"))
    (pad "2" smd roundrect (at 0.485 0 90) (size 0.59 0.64) (layers "B.Cu" "B.Paste" "B.Mask") (roundrect_rratio 0.25)
      (net 656 "Net-(U17-PF3)") (pintype "passive"))
  )
	(footprint "kria-k26-devboard-footprints:C_0402_1005Metric" (layer "B.Cu")
    (at 133.4 63.741421 90)
    (descr "Capacitor SMD 0402")
    (tags "capacitor SMD 0402")
    (property "Author" "Antmicro")
    (property "Dielectric" "")
    (property "License" "Apache-2.0")
    (property "MPN" "CC0402MRX5R5BB106")
    (property "Manufacturer" "Yaego")
    (property "Sheetfile" "usb.kicad_sch")
    (property "Sheetname" "USB")
    (property "Val" "10u")
    (property "Voltage" "")
    (property "ki_description" " ")
    (attr smd)
    (fp_text reference "C73" (at 3.781421 0.36 270) (layer "B.SilkS")
        (effects (font (size 0.7 0.7) (thickness 0.15)) (justify left bottom mirror))
    )
    (fp_text value "C_10u_0402" (at 0 -1.4 270) (layer "B.Fab") hide
        (effects (font (size 0.7 0.7) (thickness 0.15)) (justify left bottom mirror))
    )
    (fp_text user "${REFERENCE}" (at -0.932 -3.168 270) (layer "B.Fab") hide
        (effects (font (size 0.7 0.7) (thickness 0.15)) (justify left bottom mirror))
    )
    (fp_text user "License: Apache-2.0" (at -0.932 -5.17 270) (layer "B.Fab") hide
        (effects (font (size 0.7 0.7) (thickness 0.15)) (justify left bottom mirror))
    )
    (fp_text user "Author: Antmicro" (at -0.932 -4.17 270) (layer "B.Fab") hide
        (effects (font (size 0.7 0.7) (thickness 0.15)) (justify left bottom mirror))
    )
    (fp_rect (start -0.94 0.47) (end 0.94 -0.47)
      (stroke (width 0.05) (type solid)) (fill none) (layer "B.CrtYd"))
    (fp_rect (start -0.499 0.249) (end 0.499 -0.249)
      (stroke (width 0.15) (type solid)) (fill none) (layer "B.Fab"))
    (pad "1" smd roundrect (at -0.484 0 90) (size 0.59 0.64) (layers "B.Cu" "B.Paste" "B.Mask") (roundrect_rratio 0.25)
      (net 64 "/USB/USB1_VBUS") (pintype "passive"))
    (pad "2" smd roundrect (at 0.484 0 90) (size 0.59 0.64) (layers "B.Cu" "B.Paste" "B.Mask") (roundrect_rratio 0.25)
      (net 1 "GND") (pintype "passive"))
  )
	(footprint "kria-k26-devboard-footprints:C_0402_1005Metric" (layer "B.Cu")
    (at 118.35 67.55)
    (descr "Capacitor SMD 0402")
    (tags "capacitor SMD 0402")
    (property "Author" "Antmicro")
    (property "Dielectric" "X5R")
    (property "License" "Apache-2.0")
    (property "MPN" "GRM155R61H104KE14D")
    (property "Manufacturer" "Murata")
    (property "Sheetfile" "usb.kicad_sch")
    (property "Sheetname" "USB")
    (property "Val" "100n")
    (property "Voltage" "50V")
    (property "ki_description" " ")
    (attr smd)
    (fp_text reference "C88" (at 3.04 0.32 180) (layer "B.SilkS")
        (effects (font (size 0.7 0.7) (thickness 0.15)) (justify left bottom mirror))
    )
    (fp_text value "C_100n_0402" (at 0 -1.4 180) (layer "B.Fab") hide
        (effects (font (size 0.7 0.7) (thickness 0.15)) (justify left bottom mirror))
    )
    (fp_text user "${REFERENCE}" (at -0.932 -3.168 180) (layer "B.Fab") hide
        (effects (font (size 0.7 0.7) (thickness 0.15)) (justify left bottom mirror))
    )
    (fp_text user "Author: Antmicro" (at -0.932 -4.17 180) (layer "B.Fab") hide
        (effects (font (size 0.7 0.7) (thickness 0.15)) (justify left bottom mirror))
    )
    (fp_text user "License: Apache-2.0" (at -0.932 -5.17 180) (layer "B.Fab") hide
        (effects (font (size 0.7 0.7) (thickness 0.15)) (justify left bottom mirror))
    )
    (fp_rect (start -0.94 0.47) (end 0.94 -0.47)
      (stroke (width 0.05) (type solid)) (fill none) (layer "B.CrtYd"))
    (fp_rect (start -0.499 0.249) (end 0.499 -0.249)
      (stroke (width 0.15) (type solid)) (fill none) (layer "B.Fab"))
    (pad "1" smd roundrect (at -0.484 0) (size 0.59 0.64) (layers "B.Cu" "B.Paste" "B.Mask") (roundrect_rratio 0.25)
      (net 87 "/USB/USB4_VBUS") (pintype "passive"))
    (pad "2" smd roundrect (at 0.484 0) (size 0.59 0.64) (layers "B.Cu" "B.Paste" "B.Mask") (roundrect_rratio 0.25)
      (net 1 "GND") (pintype "passive"))
  )
	(footprint "kria-k26-devboard-footprints:C_0402_1005Metric" (layer "B.Cu")
    (at 151.845911 88.814035 180)
    (descr "Capacitor SMD 0402")
    (tags "capacitor SMD 0402")
    (property "Author" "Antmicro")
    (property "Dielectric" "")
    (property "License" "Apache-2.0")
    (property "MPN" "C1005X6S1A105K050BC")
    (property "Manufacturer" "TDK")
    (property "Sheetfile" "eth.kicad_sch")
    (property "Sheetname" "Ethernet")
    (property "Val" "1u")
    (property "Voltage" "")
    (property "ki_description" " ")
    (attr smd)
    (fp_text reference "C112" (at 0.87 -0.41) (layer "B.SilkS")
        (effects (font (size 0.7 0.7) (thickness 0.15)) (justify left bottom mirror))
    )
    (fp_text value "C_1u_0402" (at 0 -1.4) (layer "B.Fab") hide
        (effects (font (size 0.7 0.7) (thickness 0.15)) (justify left bottom mirror))
    )
    (fp_text user "Author: Antmicro" (at -0.932 -4.17) (layer "B.Fab") hide
        (effects (font (size 0.7 0.7) (thickness 0.15)) (justify left bottom mirror))
    )
    (fp_text user "${REFERENCE}" (at -0.932 -3.168) (layer "B.Fab") hide
        (effects (font (size 0.7 0.7) (thickness 0.15)) (justify left bottom mirror))
    )
    (fp_text user "License: Apache-2.0" (at -0.932 -5.17) (layer "B.Fab") hide
        (effects (font (size 0.7 0.7) (thickness 0.15)) (justify left bottom mirror))
    )
    (fp_rect (start -0.94 0.47) (end 0.94 -0.47)
      (stroke (width 0.05) (type solid)) (fill none) (layer "B.CrtYd"))
    (fp_rect (start -0.499 0.249) (end 0.499 -0.249)
      (stroke (width 0.15) (type solid)) (fill none) (layer "B.Fab"))
    (pad "1" smd roundrect (at -0.484 0 180) (size 0.59 0.64) (layers "B.Cu" "B.Paste" "B.Mask") (roundrect_rratio 0.25)
      (net 19 "PS_1V0") (pintype "passive"))
    (pad "2" smd roundrect (at 0.484 0 180) (size 0.59 0.64) (layers "B.Cu" "B.Paste" "B.Mask") (roundrect_rratio 0.25)
      (net 1 "GND") (pintype "passive"))
  )
	(footprint "kria-k26-devboard-footprints:C_0402_1005Metric" (layer "B.Cu")
    (at 145.888373 89.9)
    (descr "Capacitor SMD 0402")
    (tags "capacitor SMD 0402")
    (property "Author" "Antmicro")
    (property "Dielectric" "X5R")
    (property "License" "Apache-2.0")
    (property "MPN" "GRM155R61H104KE14D")
    (property "Manufacturer" "Murata")
    (property "Sheetfile" "eth.kicad_sch")
    (property "Sheetname" "Ethernet")
    (property "Val" "100n")
    (property "Voltage" "50V")
    (property "ki_description" " ")
    (attr smd)
    (fp_text reference "C99" (at -0.935911 0.4 180) (layer "B.SilkS")
        (effects (font (size 0.7 0.7) (thickness 0.15)) (justify left bottom mirror))
    )
    (fp_text value "C_100n_0402" (at 0 -1.4 180) (layer "B.Fab") hide
        (effects (font (size 0.7 0.7) (thickness 0.15)) (justify left bottom mirror))
    )
    (fp_text user "${REFERENCE}" (at -0.932 -3.168 180) (layer "B.Fab") hide
        (effects (font (size 0.7 0.7) (thickness 0.15)) (justify left bottom mirror))
    )
    (fp_text user "Author: Antmicro" (at -0.932 -4.17 180) (layer "B.Fab") hide
        (effects (font (size 0.7 0.7) (thickness 0.15)) (justify left bottom mirror))
    )
    (fp_text user "License: Apache-2.0" (at -0.932 -5.17 180) (layer "B.Fab") hide
        (effects (font (size 0.7 0.7) (thickness 0.15)) (justify left bottom mirror))
    )
    (fp_rect (start -0.94 0.47) (end 0.94 -0.47)
      (stroke (width 0.05) (type solid)) (fill none) (layer "B.CrtYd"))
    (fp_rect (start -0.499 0.249) (end 0.499 -0.249)
      (stroke (width 0.15) (type solid)) (fill none) (layer "B.Fab"))
    (pad "1" smd roundrect (at -0.484 0) (size 0.59 0.64) (layers "B.Cu" "B.Paste" "B.Mask") (roundrect_rratio 0.25)
      (net 17 "PS_1V8") (pintype "passive"))
    (pad "2" smd roundrect (at 0.484 0) (size 0.59 0.64) (layers "B.Cu" "B.Paste" "B.Mask") (roundrect_rratio 0.25)
      (net 1 "GND") (pintype "passive"))
  )
	(footprint "kria-k26-devboard-footprints:R_0402_1005Metric" (layer "B.Cu")
    (at 141.315 84.19 180)
    (descr "Resistor SMD 0402")
    (tags "resistor SMD 0402")
    (property "Author" "Antmicro")
    (property "License" "Apache-2.0")
    (property "MPN" "CR0402-FX-5100GLF")
    (property "Manufacturer" "Bourns")
    (property "Sheetfile" "dc-dc-conventers.kicad_sch")
    (property "Sheetname" "DC/DC conventers")
    (property "Tolerance" "1%")
    (property "Val" "510R")
    (property "ki_description" "510R resistor in 0402 package with 1% tolerance")
    (attr smd)
    (fp_text reference "R128" (at -3.726 -0.37) (layer "B.SilkS")
        (effects (font (size 0.7 0.7) (thickness 0.15)) (justify left bottom mirror))
    )
    (fp_text value "R_510R_0402" (at 0 -1.4) (layer "B.Fab") hide
        (effects (font (size 0.7 0.7) (thickness 0.15)) (justify left bottom mirror))
    )
    (fp_text user "License: Apache-2.0" (at -0.95 -5.169) (layer "B.Fab") hide
        (effects (font (size 0.7 0.7) (thickness 0.15)) (justify left bottom mirror))
    )
    (fp_text user "Author: Antmicro" (at -0.95 -4.169) (layer "B.Fab") hide
        (effects (font (size 0.7 0.7) (thickness 0.15)) (justify left bottom mirror))
    )
    (fp_text user "${REFERENCE}" (at -0.95 -3.168) (layer "B.Fab") hide
        (effects (font (size 0.7 0.7) (thickness 0.15)) (justify left bottom mirror))
    )
    (fp_rect (start -0.93 0.47) (end 0.93 -0.47)
      (stroke (width 0.05) (type solid)) (fill none) (layer "B.CrtYd"))
    (fp_rect (start -0.5 0.25) (end 0.5 -0.25)
      (stroke (width 0.15) (type solid)) (fill none) (layer "B.Fab"))
    (pad "1" smd roundrect (at -0.485 0 180) (size 0.59 0.64) (layers "B.Cu" "B.Paste" "B.Mask") (roundrect_rratio 0.25)
      (net 240 "Net-(D15-Pad1)") (pintype "passive"))
    (pad "2" smd roundrect (at 0.485 0 180) (size 0.59 0.64) (layers "B.Cu" "B.Paste" "B.Mask") (roundrect_rratio 0.25)
      (net 766 "/Power Supply/DC/DC conventers/PS_2V5_OUT") (pintype "passive"))
  )
	(footprint "kria-k26-devboard-footprints:C_0603_1608Metric" (layer "B.Cu")
    (at 134.839 94.392 90)
    (descr "Capacitor SMD 0603")
    (tags "capacitor 0603")
    (property "Author" "Antmicro")
    (property "Dielectric" "")
    (property "License" "Apache-2.0")
    (property "MPN" "GRM188R60J226MEA0D")
    (property "Manufacturer" "Murata")
    (property "Sheetfile" "dc-dc-conventers.kicad_sch")
    (property "Sheetname" "DC/DC conventers")
    (property "Val" "22u")
    (property "Voltage" "")
    (property "ki_description" " ")
    (attr smd)
    (fp_text reference "C215" (at 1.582 -0.829 270) (layer "B.SilkS")
        (effects (font (size 0.7 0.7) (thickness 0.15)) (justify left bottom mirror))
    )
    (fp_text value "C_22u_0603" (at 0 -1.6 270) (layer "B.Fab") hide
        (effects (font (size 0.7 0.7) (thickness 0.15)) (justify left bottom mirror))
    )
    (fp_text user "Author: Antmicro" (at -1.682 -4.894 270) (layer "B.Fab") hide
        (effects (font (size 0.7 0.7) (thickness 0.15)) (justify left bottom mirror))
    )
    (fp_text user "License: Apache-2.0" (at -1.682 -5.895 270) (layer "B.Fab") hide
        (effects (font (size 0.7 0.7) (thickness 0.15)) (justify left bottom mirror))
    )
    (fp_text user "${REFERENCE}" (at -1.682 -3.895 270) (layer "B.Fab") hide
        (effects (font (size 0.7 0.7) (thickness 0.15)) (justify left bottom mirror))
    )
    (fp_line (start -0.3 -0.3) (end 0.3 -0.3)
      (stroke (width 0.15) (type solid)) (layer "B.SilkS"))
    (fp_line (start -0.3 0.3) (end 0.3 0.3)
      (stroke (width 0.15) (type solid)) (layer "B.SilkS"))
    (fp_rect (start -1.24 0.7) (end 1.24 -0.7)
      (stroke (width 0.05) (type solid)) (fill none) (layer "B.CrtYd"))
    (fp_rect (start -0.8 0.4) (end 0.8 -0.4)
      (stroke (width 0.15) (type solid)) (fill none) (layer "B.Fab"))
    (pad "1" smd roundrect (at -0.7 0 90) (size 0.6 0.8) (layers "B.Cu" "B.Paste" "B.Mask") (roundrect_rratio 0.2)
      (net 769 "/Power Supply/DC/DC conventers/PS_1V0_OUT") (pintype "passive"))
    (pad "2" smd roundrect (at 0.7 0 90) (size 0.6 0.8) (layers "B.Cu" "B.Paste" "B.Mask") (roundrect_rratio 0.2)
      (net 1 "GND") (pintype "passive"))
  )
	(footprint "kria-k26-devboard-footprints:R_0402_1005Metric" (layer "B.Cu")
    (at 139.100001 89.05 180)
    (descr "Resistor SMD 0402")
    (tags "resistor SMD 0402")
    (property "Author" "Antmicro")
    (property "License" "Apache-2.0")
    (property "MPN" "CR0402-FX-1002GLF")
    (property "Manufacturer" "Bourns")
    (property "Sheetfile" "dc-dc-conventers.kicad_sch")
    (property "Sheetname" "DC/DC conventers")
    (property "Tolerance" "1%")
    (property "Val" "10k")
    (property "ki_description" "10k resistor in 0402 package with 1% tolerance")
    (attr smd)
    (fp_text reference "R140" (at -3.669999 -0.32) (layer "B.SilkS")
        (effects (font (size 0.7 0.7) (thickness 0.15)) (justify left bottom mirror))
    )
    (fp_text value "R_10k_0402" (at 0 -1.4) (layer "B.Fab") hide
        (effects (font (size 0.7 0.7) (thickness 0.15)) (justify left bottom mirror))
    )
    (fp_text user "${REFERENCE}" (at -0.95 -3.168) (layer "B.Fab") hide
        (effects (font (size 0.7 0.7) (thickness 0.15)) (justify left bottom mirror))
    )
    (fp_text user "License: Apache-2.0" (at -0.95 -5.169) (layer "B.Fab") hide
        (effects (font (size 0.7 0.7) (thickness 0.15)) (justify left bottom mirror))
    )
    (fp_text user "Author: Antmicro" (at -0.95 -4.169) (layer "B.Fab") hide
        (effects (font (size 0.7 0.7) (thickness 0.15)) (justify left bottom mirror))
    )
    (fp_rect (start -0.93 0.47) (end 0.93 -0.47)
      (stroke (width 0.05) (type solid)) (fill none) (layer "B.CrtYd"))
    (fp_rect (start -0.5 0.25) (end 0.5 -0.25)
      (stroke (width 0.15) (type solid)) (fill none) (layer "B.Fab"))
    (pad "1" smd roundrect (at -0.485 0 180) (size 0.59 0.64) (layers "B.Cu" "B.Paste" "B.Mask") (roundrect_rratio 0.25)
      (net 692 "Net-(U53-FB)") (pintype "passive"))
    (pad "2" smd roundrect (at 0.485 0 180) (size 0.59 0.64) (layers "B.Cu" "B.Paste" "B.Mask") (roundrect_rratio 0.25)
      (net 1 "GND") (pintype "passive"))
  )
	(footprint "kria-k26-devboard-footprints:C_0402_1005Metric" (layer "B.Cu")
    (at 151.58 115.06 180)
    (descr "Capacitor SMD 0402")
    (tags "capacitor SMD 0402")
    (property "Author" "Antmicro")
    (property "Dielectric" "X5R")
    (property "License" "Apache-2.0")
    (property "MPN" "GRM155R61H104KE14D")
    (property "Manufacturer" "Murata")
    (property "Sheetfile" "debug.kicad_sch")
    (property "Sheetname" "Debug and JTAG")
    (property "Val" "100n")
    (property "Voltage" "50V")
    (property "ki_description" " ")
    (attr smd)
    (fp_text reference "C146" (at -3.74 -0.37) (layer "B.SilkS")
        (effects (font (size 0.7 0.7) (thickness 0.15)) (justify left bottom mirror))
    )
    (fp_text value "C_100n_0402" (at 0 -1.4) (layer "B.Fab") hide
        (effects (font (size 0.7 0.7) (thickness 0.15)) (justify left bottom mirror))
    )
    (fp_text user "${REFERENCE}" (at -0.932 -3.168) (layer "B.Fab") hide
        (effects (font (size 0.7 0.7) (thickness 0.15)) (justify left bottom mirror))
    )
    (fp_text user "Author: Antmicro" (at -0.932 -4.17) (layer "B.Fab") hide
        (effects (font (size 0.7 0.7) (thickness 0.15)) (justify left bottom mirror))
    )
    (fp_text user "License: Apache-2.0" (at -0.932 -5.17) (layer "B.Fab") hide
        (effects (font (size 0.7 0.7) (thickness 0.15)) (justify left bottom mirror))
    )
    (fp_rect (start -0.94 0.47) (end 0.94 -0.47)
      (stroke (width 0.05) (type solid)) (fill none) (layer "B.CrtYd"))
    (fp_rect (start -0.499 0.249) (end 0.499 -0.249)
      (stroke (width 0.15) (type solid)) (fill none) (layer "B.Fab"))
    (pad "1" smd roundrect (at -0.484 0 180) (size 0.59 0.64) (layers "B.Cu" "B.Paste" "B.Mask") (roundrect_rratio 0.25)
      (net 138 "/Debug and JTAG/USB_3V3") (pintype "passive"))
    (pad "2" smd roundrect (at 0.484 0 180) (size 0.59 0.64) (layers "B.Cu" "B.Paste" "B.Mask") (roundrect_rratio 0.25)
      (net 1 "GND") (pintype "passive"))
  )
)
